# T6G (Grand Teton) — schematic netlist excerpt (pin names and nets, part order shuffled) for the footprints in the layout excerpt that follows; sources: Cadence DE-HDL packaged netlist, KiCad conversion of 04192023_DAF0TMB3IC0_F0TG_MB_C_brd_V02_OCP.brd

H113  GND_HOLE  EMPTY  pkg TH  page 230
  GND2  = GND
  GND3  = GND
  GND4  = GND
  GND5  = GND
  GND6  = GND
  GND7  = GND
  GND8  = GND
  GND9  = GND

C734  Q_CAP_DIFFBUS  DIFF BUS_0.22UF 6.3V 20% X6S  pkg C0201  page 66 : \1\ = P5E_CPU1_P1_TX_C_DN<3> ; \2\ = P5E_CPU1_P1_TX_DN<3>

(kicad_pcb
	(version 20260206)
	(generator "pcbnew")
	(generator_version "10.0")
	(general
		(thickness 1.6)
		(legacy_teardrops no)
	)
	(paper "A4")
	(title_block
		(title "04192023_DAF0TMB3IC0_F0TG_MB_C_brd_V02_OCP.brd")
		(comment 1 "Grand Teton / footprints 2039-2040 of 8354")
	)
	(layers
		(0 "F.Cu" signal "TOP")
		(4 "In1.Cu" signal "GND")
		(6 "In2.Cu" signal "IN1")
		(8 "In3.Cu" signal "GND1")
		(10 "In4.Cu" signal "IN2")
		(12 "In5.Cu" signal "GND2")
		(14 "In6.Cu" signal "IN3")
		(16 "In7.Cu" signal "GND3")
		(18 "In8.Cu" signal "VCC")
		(20 "In9.Cu" signal "VCC1")
		(22 "In10.Cu" signal "GND4")
		(24 "In11.Cu" signal "IN4")
		(26 "In12.Cu" signal "GND5")
		(28 "In13.Cu" signal "IN5")
		(30 "In14.Cu" signal "GND6")
		(32 "In15.Cu" signal "IN6")
		(34 "In16.Cu" signal "GND7")
		(2 "B.Cu" signal "BOTTOM")
		(9 "F.Adhes" user "F.Adhesive")
		(11 "B.Adhes" user "B.Adhesive")
		(13 "F.Paste" user "Package Geometry/Pastemask Top")
		(15 "B.Paste" user "Package Geometry/Pastemask Bottom")
		(5 "F.SilkS" user "Ref Des/Silkscreen Top")
		(7 "B.SilkS" user "Ref Des/Silkscreen Bottom")
		(1 "F.Mask" user "Board Geometry/Soldermask Top")
		(3 "B.Mask" user "Board Geometry/Soldermask Bottom")
		(17 "Dwgs.User" user "User.Drawings")
		(19 "Cmts.User" user "User.Comments")
		(21 "Eco1.User" user "User.Eco1")
		(23 "Eco2.User" user "User.Eco2")
		(25 "Edge.Cuts" user "Board Geometry/Outline")
		(27 "Margin" user)
		(31 "F.CrtYd" user "Package Geometry/Place Bound Top")
		(29 "B.CrtYd" user "Package Geometry/Place Bound Bottom")
		(35 "F.Fab" user "Ref Des/Assembly Top")
		(33 "B.Fab" user "Ref Des/Assembly Bottom")
	)
	(footprint ""
		(layer "F.Cu")
		(at 204.64526 -51.999896)
		(property "Reference" "H113"
			(at -9.058656 -6.511544 0)
			(unlocked yes)
			(layer "F.SilkS")
			(effects
				(font
					(size 0.7874 0.5842)
					(thickness 0.1524)
				)
				(justify left)
			)
		)
		(property "Value" ""
			(at 0 0 0)
			(layer "F.Fab")
			(effects
				(font
					(size 1.27 1.27)
				)
			)
		)
		(duplicate_pad_numbers_are_jumpers no)
		(fp_circle
			(center 0 0)
			(end 7.999984 0)
			(stroke
				(width 0.1524)
				(type default)
			)
			(fill no)
			(layer "F.SilkS")
		)
		(fp_circle
			(center 0 0)
			(end 7.999984 0)
			(stroke
				(width 0.1524)
				(type default)
			)
			(fill no)
			(layer "B.SilkS")
		)
		(fp_circle
			(center 0 0)
			(end 7.999984 0)
			(stroke
				(width 0.1)
				(type default)
			)
			(fill no)
			(layer "B.Fab")
		)
		(fp_circle
			(center 0 0)
			(end 7.999984 0)
			(stroke
				(width 0.1)
				(type default)
			)
			(fill no)
			(layer "F.Fab")
		)
		(pad "" np_thru_hole circle
			(at 0 0)
			(size 5.5118 5.5118)
			(drill 5.5118)
			(layers "*.Cu" "*.Mask")
			(clearance 0.381)
			(thermal_gap 0.381)
		)
		(pad "2" thru_hole circle
			(at 0 -3.999992)
			(size 0.762 0.762)
			(drill 0.5588)
			(layers "*.Cu" "*.Mask")
			(remove_unused_layers no)
			(net "GND")
			(clearance 0.1524)
			(thermal_gap 0.1524)
		)
		(pad "3" thru_hole circle
			(at -2.999994 -2.500122)
			(size 0.762 0.762)
			(drill 0.5588)
			(layers "*.Cu" "*.Mask")
			(remove_unused_layers no)
			(net "GND")
			(clearance 0.1524)
			(thermal_gap 0.1524)
		)
		(pad "4" thru_hole circle
			(at -3.999992 0)
			(size 0.762 0.762)
			(drill 0.5588)
			(layers "*.Cu" "*.Mask")
			(remove_unused_layers no)
			(net "GND")
			(clearance 0.1524)
			(thermal_gap 0.1524)
		)
		(pad "5" thru_hole circle
			(at -2.999994 2.500122)
			(size 0.762 0.762)
			(drill 0.5588)
			(layers "*.Cu" "*.Mask")
			(remove_unused_layers no)
			(net "GND")
			(clearance 0.1524)
			(thermal_gap 0.1524)
		)
		(pad "6" thru_hole circle
			(at 0 3.999992)
			(size 0.762 0.762)
			(drill 0.5588)
			(layers "*.Cu" "*.Mask")
			(remove_unused_layers no)
			(net "GND")
			(clearance 0.1524)
			(thermal_gap 0.1524)
		)
		(pad "7" thru_hole circle
			(at 2.999994 2.500122)
			(size 0.762 0.762)
			(drill 0.5588)
			(layers "*.Cu" "*.Mask")
			(remove_unused_layers no)
			(net "GND")
			(clearance 0.1524)
			(thermal_gap 0.1524)
		)
		(pad "8" thru_hole circle
			(at 3.999992 0)
			(size 0.762 0.762)
			(drill 0.5588)
			(layers "*.Cu" "*.Mask")
			(remove_unused_layers no)
			(net "GND")
			(clearance 0.1524)
			(thermal_gap 0.1524)
		)
		(pad "9" thru_hole circle
			(at 2.999994 -2.500122)
			(size 0.762 0.762)
			(drill 0.5588)
			(layers "*.Cu" "*.Mask")
			(remove_unused_layers no)
			(net "GND")
			(clearance 0.1524)
			(thermal_gap 0.1524)
		)
		(zone
			(layer "F.Cu")
			(hatch none 0.5)
			(connect_pads
				(clearance 0)
			)
			(min_thickness 0.25)
			(keepout
				(tracks not_allowed)
				(vias allowed)
				(pads allowed)
				(copperpour not_allowed)
				(footprints allowed)
			)
			(placement
				(enabled no)
				(sheetname "")
			)
			(fill
				(thermal_gap 0.5)
				(thermal_bridge_width 0.5)
				(island_removal_mode 0)
			)
			(polygon
				(pts
					(arc
						(start 204.64526 -59.99988)
						(mid 198.988417 -57.656739)
						(end 196.645276 -51.999896)
					)
					(arc
						(start 196.645276 -51.999896)
						(mid 198.988417 -46.343053)
						(end 204.64526 -43.999912)
					)
					(xy 204.64526 -46.74616) (xy 204.594206 -46.74616)
					(arc
						(start 204.593952 -46.74616)
						(mid 199.391273 -51.999896)
						(end 204.593952 -57.253632)
					)
					(xy 204.594206 -57.253632) (xy 204.64526 -57.253632)
				)
			)
		)
		(zone
			(layer "F.Cu")
			(hatch none 0.5)
			(connect_pads
				(clearance 0)
			)
			(min_thickness 0.25)
			(keepout
				(tracks not_allowed)
				(vias allowed)
				(pads allowed)
				(copperpour not_allowed)
				(footprints allowed)
			)
			(placement
				(enabled no)
				(sheetname "")
			)
			(fill
				(thermal_gap 0.5)
				(thermal_bridge_width 0.5)
				(island_removal_mode 0)
			)
			(polygon
				(pts
					(arc
						(start 204.64526 -59.99988)
						(mid 210.302103 -57.656739)
						(end 212.645244 -51.999896)
					)
					(arc
						(start 212.645244 -51.999896)
						(mid 210.302103 -46.343053)
						(end 204.64526 -43.999912)
					)
					(xy 204.64526 -46.74616) (xy 204.696314 -46.74616)
					(arc
						(start 204.696568 -46.74616)
						(mid 209.899247 -51.999896)
						(end 204.696568 -57.253632)
					)
					(xy 204.696314 -57.253632) (xy 204.64526 -57.253632)
				)
			)
		)
		(zone
			(layers "F.Cu" "B.Cu" "In1.Cu" "In2.Cu" "In3.Cu" "In4.Cu" "In5.Cu" "In6.Cu"
				"In7.Cu" "In8.Cu" "In9.Cu" "In10.Cu" "In11.Cu" "In12.Cu" "In13.Cu" "In14.Cu"
				"In15.Cu" "In16.Cu"
			)
			(hatch none 0.5)
			(connect_pads
				(clearance 0)
			)
			(min_thickness 0.25)
			(keepout
				(tracks not_allowed)
				(vias allowed)
				(pads allowed)
				(copperpour not_allowed)
				(footprints allowed)
			)
			(placement
				(enabled no)
				(sheetname "")
			)
			(fill
				(thermal_gap 0.5)
				(thermal_bridge_width 0.5)
				(island_removal_mode 0)
			)
			(polygon
				(pts
					(arc
						(start 207.92186 -51.999896)
						(mid 201.36866 -51.999896)
						(end 207.92186 -51.999896)
					)
				)
			)
		)
		(zone
			(layer "B.Cu")
			(hatch none 0.5)
			(connect_pads
				(clearance 0)
			)
			(min_thickness 0.25)
			(keepout
				(tracks not_allowed)
				(vias allowed)
				(pads allowed)
				(copperpour not_allowed)
				(footprints allowed)
			)
			(placement
				(enabled no)
				(sheetname "")
			)
			(fill
				(thermal_gap 0.5)
				(thermal_bridge_width 0.5)
				(island_removal_mode 0)
			)
			(polygon
				(pts
					(arc
						(start 204.64526 -57.507886)
						(mid 199.13727 -51.999896)
						(end 204.64526 -46.491906)
					)
					(arc
						(start 204.64526 -46.974506)
						(mid 199.61987 -51.999896)
						(end 204.64526 -57.025286)
					)
				)
			)
		)
		(zone
			(layer "B.Cu")
			(hatch none 0.5)
			(connect_pads
				(clearance 0)
			)
			(min_thickness 0.25)
			(keepout
				(tracks not_allowed)
				(vias allowed)
				(pads allowed)
				(copperpour not_allowed)
				(footprints allowed)
			)
			(placement
				(enabled no)
				(sheetname "")
			)
			(fill
				(thermal_gap 0.5)
				(thermal_bridge_width 0.5)
				(island_removal_mode 0)
			)
			(polygon
				(pts
					(arc
						(start 204.64526 -57.507886)
						(mid 210.15325 -51.999896)
						(end 204.64526 -46.491906)
					)
					(arc
						(start 204.64526 -46.974506)
						(mid 209.67065 -51.999896)
						(end 204.64526 -57.025286)
					)
				)
			)
		)
	)
	(footprint ""
		(layer "F.Cu")
		(at 78.133702 -370.57203 -90)
		(property "Reference" "C734"
			(at 0 0 270)
			(layer "F.SilkS")
			(hide yes)
			(effects
				(font
					(size 1.27 1.27)
				)
			)
		)
		(property "Value" ""
			(at 0 0 270)
			(layer "F.Fab")
			(effects
				(font
					(size 1.27 1.27)
				)
			)
		)
		(duplicate_pad_numbers_are_jumpers no)
		(fp_line
			(start -0.299974 0.150114)
			(end -0.299974 -0.150114)
			(stroke
				(width 0.1)
				(type default)
			)
			(layer "F.Fab")
		)
		(fp_line
			(start 0.299974 0.150114)
			(end -0.299974 0.150114)
			(stroke
				(width 0.1)
				(type default)
			)
			(layer "F.Fab")
		)
		(fp_line
			(start -0.299974 -0.150114)
			(end 0.299974 -0.150114)
			(stroke
				(width 0.1)
				(type default)
			)
			(layer "F.Fab")
		)
		(fp_line
			(start 0.299974 -0.150114)
			(end 0.299974 0.150114)
			(stroke
				(width 0.1)
				(type default)
			)
			(layer "F.Fab")
		)
		(pad "1" smd rect
			(at -0.2667 0 270)
			(size 0.3048 0.381)
			(layers "F.Cu" "F.Mask" "F.Paste")
			(net "P5E_CPU1_P1_TX_C_DN<3>")
		)
		(pad "2" smd rect
			(at 0.2667 0 270)
			(size 0.3048 0.381)
			(layers "F.Cu" "F.Mask" "F.Paste")
			(net "P5E_CPU1_P1_TX_DN<3>")
		)
	)
)
